(kicad_pcb
	(version 20241229)
	(generator "pcbnew")
	(generator_version "9.0")
	(general
		(thickness 1.61)
		(legacy_teardrops no)
	)
	(paper "A3")
	(title_block
		(title "RDIMM DDR5 Tester")
		(date "2026-05-21")
		(rev "2.2.0")
		(company "Antmicro")
		(comment 9 "footprints 190-194 of 796")
	)
	(layers
		(0 "F.Cu" signal)
		(4 "In1.Cu" power)
		(6 "In2.Cu" mixed)
		(8 "In3.Cu" power)
		(10 "In4.Cu" mixed)
		(12 "In5.Cu" power)
		(14 "In6.Cu" mixed)
		(16 "In7.Cu" power)
		(18 "In8.Cu" power)
		(20 "In9.Cu" mixed)
		(22 "In10.Cu" power)
		(2 "B.Cu" signal)
		(9 "F.Adhes" user "F.Adhesive")
		(11 "B.Adhes" user "B.Adhesive")
		(13 "F.Paste" user)
		(15 "B.Paste" user)
		(5 "F.SilkS" user "F.Silkscreen")
		(7 "B.SilkS" user "B.Silkscreen")
		(1 "F.Mask" user)
		(3 "B.Mask" user)
		(17 "Dwgs.User" user "User.Drawings")
		(19 "Cmts.User" user "User.Comments")
		(21 "Eco1.User" user "User.Eco1")
		(23 "Eco2.User" user "User.Eco2")
		(25 "Edge.Cuts" user)
		(27 "Margin" user)
		(31 "F.CrtYd" user "F.Courtyard")
		(29 "B.CrtYd" user "B.Courtyard")
		(35 "F.Fab" user)
		(33 "B.Fab" user)
	)
	(footprint "antmicro-footprints:C_0603_1608Metric"
		(layer "F.Cu")
		(at 221.955 170.109999 180)
		(descr "Capacitor SMD 0603")
		(tags "capacitor 0603")
		(property "Reference" "C220"
			(at -3.42 -3.015001 0)
			(layer "F.SilkS")
			(effects
				(font
					(size 0.7 0.7)
					(thickness 0.15)
				)
				(justify right bottom)
			)
		)
		(property "Value" "C_22u_0603"
			(at -1.42757 1.770288 0)
			(layer "F.Fab")
			(effects
				(font
					(size 0.7 0.7)
					(thickness 0.15)
				)
				(justify right bottom)
			)
		)
		(property "Datasheet" "https://www.murata.com/products/productdetail?partno=GRM188R60J226MEA0%23"
			(at 0 0 180)
			(layer "F.Fab")
			(hide yes)
			(effects
				(font
					(size 1.27 1.27)
					(thickness 0.15)
				)
			)
		)
		(property "Manufacturer" "Murata"
			(at 0 0 180)
			(unlocked yes)
			(layer "F.Fab")
			(hide yes)
			(effects
				(font
					(size 1 1)
					(thickness 0.15)
				)
			)
		)
		(property "MPN" "GRM188R60J226MEA0D"
			(at 0 0 180)
			(unlocked yes)
			(layer "F.Fab")
			(hide yes)
			(effects
				(font
					(size 1 1)
					(thickness 0.15)
				)
			)
		)
		(property "Val" "22u"
			(at 0 0 180)
			(unlocked yes)
			(layer "F.Fab")
			(hide yes)
			(effects
				(font
					(size 1 1)
					(thickness 0.15)
				)
			)
		)
		(property "License" "Apache-2.0"
			(at 0 0 180)
			(unlocked yes)
			(layer "F.Fab")
			(hide yes)
			(effects
				(font
					(size 1 1)
					(thickness 0.15)
				)
			)
		)
		(property "Author" "Antmicro"
			(at 0 0 180)
			(unlocked yes)
			(layer "F.Fab")
			(hide yes)
			(effects
				(font
					(size 1 1)
					(thickness 0.15)
				)
			)
		)
		(property "Voltage" ""
			(at 0 0 180)
			(unlocked yes)
			(layer "F.Fab")
			(hide yes)
			(effects
				(font
					(size 1 1)
					(thickness 0.15)
				)
			)
		)
		(property "Dielectric" ""
			(at 0 0 180)
			(unlocked yes)
			(layer "F.Fab")
			(hide yes)
			(effects
				(font
					(size 1 1)
					(thickness 0.15)
				)
			)
		)
		(sheetname "/Supply/DC-DC VCCINT/")
		(sheetfile "dc-dc-vccint.kicad_sch")
		(attr smd)
		(fp_line
			(start -0.15 0.4)
			(end 0.15 0.4)
			(stroke
				(width 0.15)
				(type solid)
			)
			(layer "F.SilkS")
		)
		(fp_line
			(start -0.15 -0.4)
			(end 0.15 -0.4)
			(stroke
				(width 0.15)
				(type solid)
			)
			(layer "F.SilkS")
		)
		(fp_rect
			(start -1.25 -0.65)
			(end 1.25 0.65)
			(stroke
				(width 0.05)
				(type solid)
			)
			(fill no)
			(layer "F.CrtYd")
		)
		(fp_rect
			(start -0.8 -0.4)
			(end 0.8 0.4)
			(stroke
				(width 0.15)
				(type solid)
			)
			(fill no)
			(layer "F.Fab")
		)
		(fp_text user "Author: Antmicro"
			(at -1.682 4.894 180)
			(layer "F.Fab")
			(effects
				(font
					(size 0.7 0.7)
					(thickness 0.15)
				)
				(justify left bottom)
			)
		)
		(fp_text user "License: Apache-2.0"
			(at -1.682 5.895 180)
			(layer "F.Fab")
			(effects
				(font
					(size 0.7 0.7)
					(thickness 0.15)
				)
				(justify left bottom)
			)
		)
		(fp_text user "${REFERENCE}"
			(at -1.682 3.895 180)
			(layer "F.Fab")
			(effects
				(font
					(size 0.7 0.7)
					(thickness 0.15)
				)
				(justify left bottom)
			)
		)
		(pad "1" smd roundrect
			(at -0.7 0 180)
			(size 0.8 1)
			(layers "F.Cu" "F.Mask" "F.Paste")
			(roundrect_rratio 0.2)
			(net 1 "GND")
			(pintype "passive")
		)
		(pad "2" smd roundrect
			(at 0.7 0 180)
			(size 0.8 1)
			(layers "F.Cu" "F.Mask" "F.Paste")
			(roundrect_rratio 0.2)
			(net 223 "/Supply/DC-DC VCCINT/0V85_REG0")
			(pintype "passive")
		)
	)
	(footprint "antmicro-footprints:LED_RGY_1.6x1.6mm_APTF1616"
		(layer "F.Cu")
		(at 254.1 145.05)
		(descr "1.6 x 1.6 mm Full-Color Surface Mount LED")
		(tags "LED")
		(property "Reference" "D20"
			(at -0.3 1.95 180)
			(layer "F.SilkS")
			(effects
				(font
					(size 0.7 0.7)
					(thickness 0.15)
				)
				(justify left bottom)
			)
		)
		(property "Value" "LED_RGY_0606_APTF1616SURKCGKSYKC"
			(at 0 2 0)
			(layer "F.Fab")
			(effects
				(font
					(size 0.7 0.7)
					(thickness 0.15)
				)
				(justify left bottom)
			)
		)
		(property "Datasheet" "https://www.kingbrightusa.com/images/catalog/SPEC/APTF1616SURKCGKSYKC.pdf"
			(at 0 0 0)
			(layer "F.Fab")
			(hide yes)
			(effects
				(font
					(size 1.27 1.27)
					(thickness 0.15)
				)
			)
		)
		(property "MPN" "APTF1616SURKCGKSYKC"
			(at 0 0 0)
			(unlocked yes)
			(layer "F.Fab")
			(hide yes)
			(effects
				(font
					(size 1 1)
					(thickness 0.15)
				)
			)
		)
		(property "Manufacturer" "Kingbright"
			(at 0 0 0)
			(unlocked yes)
			(layer "F.Fab")
			(hide yes)
			(effects
				(font
					(size 1 1)
					(thickness 0.15)
				)
			)
		)
		(property "Color" "R, G, Y"
			(at 0 0 0)
			(unlocked yes)
			(layer "F.Fab")
			(hide yes)
			(effects
				(font
					(size 1 1)
					(thickness 0.15)
				)
			)
		)
		(property "Author" "Antmicro"
			(at 0 0 0)
			(unlocked yes)
			(layer "F.Fab")
			(hide yes)
			(effects
				(font
					(size 1 1)
					(thickness 0.15)
				)
			)
		)
		(property "License" "Apache-2.0"
			(at 0 0 0)
			(unlocked yes)
			(layer "F.Fab")
			(hide yes)
			(effects
				(font
					(size 1 1)
					(thickness 0.15)
				)
			)
		)
		(sheetname "/DDR5 RDIMM/")
		(sheetfile "ddr5-rdimm.kicad_sch")
		(attr smd)
		(fp_line
			(start -0.8 -0.15)
			(end -0.801 0.15)
			(stroke
				(width 0.15)
				(type solid)
			)
			(layer "F.SilkS")
		)
		(fp_line
			(start -0.35 0.8)
			(end 0.35 0.8)
			(stroke
				(width 0.15)
				(type solid)
			)
			(layer "F.SilkS")
		)
		(fp_line
			(start 0.35 -0.802)
			(end -0.35 -0.802)
			(stroke
				(width 0.15)
				(type solid)
			)
			(layer "F.SilkS")
		)
		(fp_line
			(start 0.8 0.148)
			(end 0.8 -0.102)
			(stroke
				(width 0.15)
				(type solid)
			)
			(layer "F.SilkS")
		)
		(fp_circle
			(center -1.05 -0.95)
			(end -1.101 -0.999)
			(stroke
				(width 0.15)
				(type solid)
			)
			(fill yes)
			(layer "F.SilkS")
		)
		(fp_rect
			(start 1.3 1.1)
			(end -1.3 -1.1)
			(stroke
				(width 0.05)
				(type solid)
			)
			(fill no)
			(layer "F.CrtYd")
		)
		(fp_rect
			(start -0.801 -0.802)
			(end 0.8 0.801)
			(stroke
				(width 0.15)
				(type solid)
			)
			(fill no)
			(layer "F.Fab")
		)
		(fp_text user "Author: Antmicro"
			(at -1.3 4.496 0)
			(layer "F.Fab")
			(effects
				(font
					(size 0.7 0.7)
					(thickness 0.15)
				)
				(justify left bottom)
			)
		)
		(fp_text user "License: Apache-2.0"
			(at -1.3 5.698 0)
			(layer "F.Fab")
			(effects
				(font
					(size 0.7 0.7)
					(thickness 0.15)
				)
				(justify left bottom)
			)
		)
		(fp_text user "${REFERENCE}"
			(at -1.3 3.297 0)
			(layer "F.Fab")
			(effects
				(font
					(size 0.7 0.7)
					(thickness 0.15)
				)
				(justify left bottom)
			)
		)
		(pad "1" smd rect
			(at -0.874 -0.499 270)
			(size 0.5 0.85)
			(layers "F.Cu" "F.Mask" "F.Paste")
			(net 151 "+3V3")
			(pinfunction "A")
			(pintype "passive")
		)
		(pad "2" smd rect
			(at 0.874 -0.499 270)
			(size 0.5 0.85)
			(layers "F.Cu" "F.Mask" "F.Paste")
			(net 221 "Net-(D20-C_{R})")
			(pinfunction "C_{R}")
			(pintype "passive")
		)
		(pad "3" smd rect
			(at 0.874 0.498 270)
			(size 0.5 0.85)
			(layers "F.Cu" "F.Mask" "F.Paste")
			(net 236 "Net-(D20-C_{G})")
			(pinfunction "C_{G}")
			(pintype "passive")
		)
		(pad "4" smd rect
			(at -0.874 0.498 270)
			(size 0.5 0.85)
			(layers "F.Cu" "F.Mask" "F.Paste")
			(net 237 "Net-(D20-C_{Y})")
			(pinfunction "C_{Y}")
			(pintype "passive")
		)
	)
	(footprint "antmicro-footprints:R_1206_3216Metric"
		(layer "F.Cu")
		(at 246.299499 160.149 180)
		(property "Reference" "R145"
			(at -2.400501 -2.201 0)
			(layer "F.SilkS")
			(effects
				(font
					(size 0.7 0.7)
					(thickness 0.15)
				)
				(justify right bottom)
			)
		)
		(property "Value" "R_0R01_1206"
			(at -2.422356 2.103591 0)
			(layer "F.Fab")
			(effects
				(font
					(size 0.7 0.7)
					(thickness 0.15)
				)
				(justify right bottom)
			)
		)
		(property "Datasheet" "https://www.yageo.com/upload/media/product/productsearch/datasheet/rchip/PYu-RL_Group_521_RoHS_L_2.pdf"
			(at 0 0 180)
			(layer "F.Fab")
			(hide yes)
			(effects
				(font
					(size 1.27 1.27)
					(thickness 0.15)
				)
			)
		)
		(property "Manufacturer" "YAGEO"
			(at 0 0 180)
			(unlocked yes)
			(layer "F.Fab")
			(hide yes)
			(effects
				(font
					(size 1 1)
					(thickness 0.15)
				)
			)
		)
		(property "MPN" "RL1206FR-7W0R01L"
			(at 0 0 180)
			(unlocked yes)
			(layer "F.Fab")
			(hide yes)
			(effects
				(font
					(size 1 1)
					(thickness 0.15)
				)
			)
		)
		(property "Val" "0R01"
			(at 0 0 180)
			(unlocked yes)
			(layer "F.Fab")
			(hide yes)
			(effects
				(font
					(size 1 1)
					(thickness 0.15)
				)
			)
		)
		(property "License" "Apache-2.0"
			(at 0 0 180)
			(unlocked yes)
			(layer "F.Fab")
			(hide yes)
			(effects
				(font
					(size 1 1)
					(thickness 0.15)
				)
			)
		)
		(property "Author" "Antmicro"
			(at 0 0 180)
			(unlocked yes)
			(layer "F.Fab")
			(hide yes)
			(effects
				(font
					(size 1 1)
					(thickness 0.15)
				)
			)
		)
		(property "Tolerance" "1%"
			(at 0 0 180)
			(unlocked yes)
			(layer "F.Fab")
			(hide yes)
			(effects
				(font
					(size 1 1)
					(thickness 0.15)
				)
			)
		)
		(sheetname "/Supply/DC-DC IO/")
		(sheetfile "dc-dc-io.kicad_sch")
		(attr smd)
		(fp_line
			(start 0.8 0.901)
			(end -0.8 0.901)
			(stroke
				(width 0.15)
				(type solid)
			)
			(layer "F.SilkS")
		)
		(fp_line
			(start 0.8 -0.899)
			(end -0.8 -0.899)
			(stroke
				(width 0.15)
				(type solid)
			)
			(layer "F.SilkS")
		)
		(fp_rect
			(start -2.325 -1.15)
			(end 2.325 1.15)
			(stroke
				(width 0.05)
				(type default)
			)
			(fill no)
			(layer "F.CrtYd")
		)
		(fp_line
			(start 1.6 -0.802)
			(end 1.6 0.8)
			(stroke
				(width 0.15)
				(type solid)
			)
			(layer "F.Fab")
		)
		(fp_line
			(start -1.601 0.8)
			(end 1.6 0.8)
			(stroke
				(width 0.15)
				(type solid)
			)
			(layer "F.Fab")
		)
		(fp_line
			(start -1.601 -0.802)
			(end 1.6 -0.802)
			(stroke
				(width 0.15)
				(type solid)
			)
			(layer "F.Fab")
		)
		(fp_line
			(start -1.601 -0.802)
			(end -1.601 0.8)
			(stroke
				(width 0.15)
				(type solid)
			)
			(layer "F.Fab")
		)
		(fp_text user "${REFERENCE}"
			(at -2.401 3.5 180)
			(layer "F.Fab")
			(effects
				(font
					(size 0.7 0.7)
					(thickness 0.15)
				)
				(justify left bottom)
			)
		)
		(fp_text user "License: Apache-2.0"
			(at -2.401 6.3 180)
			(layer "F.Fab")
			(effects
				(font
					(size 0.7 0.7)
					(thickness 0.15)
				)
				(justify left bottom)
			)
		)
		(fp_text user "Author: Antmicro"
			(at -2.401 4.899 180)
			(layer "F.Fab")
			(effects
				(font
					(size 0.7 0.7)
					(thickness 0.15)
				)
				(justify left bottom)
			)
		)
		(pad "1" smd roundrect
			(at -1.5 0.001 180)
			(size 1.15 1.8)
			(layers "F.Cu" "F.Mask" "F.Paste")
			(roundrect_rratio 0.25)
			(net 45 "/Supply/DC-DC IO/3V3_local")
			(pintype "passive")
		)
		(pad "2" smd roundrect
			(at 1.5 0.001 180)
			(size 1.15 1.8)
			(layers "F.Cu" "F.Mask" "F.Paste")
			(roundrect_rratio 0.25)
			(net 151 "+3V3")
			(pintype "passive")
		)
	)
	(footprint "antmicro-footprints:C_0402_1005Metric"
		(layer "F.Cu")
		(at 164.45 164.034999)
		(descr "Capacitor SMD 0402")
		(tags "capacitor SMD 0402")
		(property "Reference" "C309"
			(at 0.82 0.44 0)
			(layer "F.SilkS")
			(effects
				(font
					(size 0.7 0.7)
					(thickness 0.15)
				)
				(justify left bottom)
			)
		)
		(property "Value" "C_100n_0402"
			(at -1.022927 2.155213 0)
			(layer "F.Fab")
			(effects
				(font
					(size 0.7 0.7)
					(thickness 0.15)
				)
				(justify left bottom)
			)
		)
		(property "Datasheet" "https://www.murata.com/products/productdetail?partno=GRM155R61H104KE14%23"
			(at 0 0 0)
			(layer "F.Fab")
			(hide yes)
			(effects
				(font
					(size 1.27 1.27)
					(thickness 0.15)
				)
			)
		)
		(property "Manufacturer" "Murata"
			(at 0 0 0)
			(unlocked yes)
			(layer "F.Fab")
			(hide yes)
			(effects
				(font
					(size 1 1)
					(thickness 0.15)
				)
			)
		)
		(property "MPN" "GRM155R61H104KE14D"
			(at 0 0 0)
			(unlocked yes)
			(layer "F.Fab")
			(hide yes)
			(effects
				(font
					(size 1 1)
					(thickness 0.15)
				)
			)
		)
		(property "Val" "100n"
			(at 0 0 0)
			(unlocked yes)
			(layer "F.Fab")
			(hide yes)
			(effects
				(font
					(size 1 1)
					(thickness 0.15)
				)
			)
		)
		(property "License" "Apache-2.0"
			(at 0 0 0)
			(unlocked yes)
			(layer "F.Fab")
			(hide yes)
			(effects
				(font
					(size 1 1)
					(thickness 0.15)
				)
			)
		)
		(property "Author" "Antmicro"
			(at 0 0 0)
			(unlocked yes)
			(layer "F.Fab")
			(hide yes)
			(effects
				(font
					(size 1 1)
					(thickness 0.15)
				)
			)
		)
		(property "Voltage" "50V"
			(at 0 0 0)
			(unlocked yes)
			(layer "F.Fab")
			(hide yes)
			(effects
				(font
					(size 1 1)
					(thickness 0.15)
				)
			)
		)
		(property "Dielectric" "X5R"
			(at 0 0 0)
			(unlocked yes)
			(layer "F.Fab")
			(hide yes)
			(effects
				(font
					(size 1 1)
					(thickness 0.15)
				)
			)
		)
		(sheetname "/FPGA MGT Interface/")
		(sheetfile "fpga-mgt.kicad_sch")
		(attr smd)
		(fp_rect
			(start -0.925 -0.47)
			(end 0.925 0.47)
			(stroke
				(width 0.05)
				(type default)
			)
			(fill no)
			(layer "F.CrtYd")
		)
		(fp_line
			(start -0.494 -0.25)
			(end 0.504 -0.25)
			(stroke
				(width 0.15)
				(type solid)
			)
			(layer "F.Fab")
		)
		(fp_line
			(start -0.494 0.248)
			(end -0.494 -0.25)
			(stroke
				(width 0.15)
				(type solid)
			)
			(layer "F.Fab")
		)
		(fp_line
			(start 0.504 -0.25)
			(end 0.504 0.248)
			(stroke
				(width 0.15)
				(type solid)
			)
			(layer "F.Fab")
		)
		(fp_line
			(start 0.504 0.248)
			(end -0.494 0.248)
			(stroke
				(width 0.15)
				(type solid)
			)
			(layer "F.Fab")
		)
		(fp_text user "Author: Antmicro"
			(at -0.939 3.399 0)
			(layer "F.Fab")
			(effects
				(font
					(size 0.7 0.7)
					(thickness 0.15)
				)
				(justify left bottom)
			)
		)
		(fp_text user "${REFERENCE}"
			(at -0.939 4.599 0)
			(layer "F.Fab")
			(effects
				(font
					(size 0.7 0.7)
					(thickness 0.15)
				)
				(justify left bottom)
			)
		)
		(fp_text user "License: Apache-2.0"
			(at -0.939 5.799 0)
			(layer "F.Fab")
			(effects
				(font
					(size 0.7 0.7)
					(thickness 0.15)
				)
				(justify left bottom)
			)
		)
		(pad "1" smd roundrect
			(at -0.48 0)
			(size 0.59 0.64)
			(layers "F.Cu" "F.Mask" "F.Paste")
			(roundrect_rratio 0.25)
			(net 389 "/FPGA MGT Interface/HDMI_SI5319_C_CLK_P")
			(pintype "passive")
		)
		(pad "2" smd roundrect
			(at 0.48 0)
			(size 0.59 0.64)
			(layers "F.Cu" "F.Mask" "F.Paste")
			(roundrect_rratio 0.25)
			(net 402 "/FPGA MGT Interface/HDMI_SI5319_CLK_P")
			(pintype "passive")
		)
	)
	(footprint "antmicro-footprints:TP_SMD_0.75mm"
		(layer "F.Cu")
		(at 155.43 160.789999)
		(property "Reference" "TP5"
			(at -2.6 0.5 0)
			(layer "F.SilkS")
			(effects
				(font
					(size 0.7 0.7)
					(thickness 0.15)
				)
				(justify left bottom)
			)
		)
		(property "Value" "TP_0.75mm_SMD"
			(at 0 1.2 0)
			(layer "F.Fab")
			(effects
				(font
					(size 0.7 0.7)
					(thickness 0.15)
				)
				(justify left bottom)
			)
		)
		(property "MPN" ""
			(at 0 0 0)
			(unlocked yes)
			(layer "F.Fab")
			(hide yes)
			(effects
				(font
					(size 1 1)
					(thickness 0.15)
				)
			)
		)
		(property "Manufacturer" ""
			(at 0 0 0)
			(unlocked yes)
			(layer "F.Fab")
			(hide yes)
			(effects
				(font
					(size 1 1)
					(thickness 0.15)
				)
			)
		)
		(property "Author" "Antmicro"
			(at 0 0 0)
			(unlocked yes)
			(layer "F.Fab")
			(hide yes)
			(effects
				(font
					(size 1 1)
					(thickness 0.15)
				)
			)
		)
		(property "License" "Apache-2.0"
			(at 0 0 0)
			(unlocked yes)
			(layer "F.Fab")
			(hide yes)
			(effects
				(font
					(size 1 1)
					(thickness 0.15)
				)
			)
		)
		(sheetname "/FPGA MGT Interface/")
		(sheetfile "fpga-mgt.kicad_sch")
		(attr exclude_from_pos_files exclude_from_bom)
		(fp_circle
			(center 0 0)
			(end 0.475 0)
			(stroke
				(width 0.05)
				(type default)
			)
			(fill no)
			(layer "F.CrtYd")
		)
		(fp_text user "${REFERENCE}"
			(at -0.4 2.7 0)
			(layer "F.Fab")
			(effects
				(font
					(size 0.7 0.7)
					(thickness 0.15)
				)
				(justify left bottom)
			)
		)
		(fp_text user "Author: Antmicro"
			(at -0.4 3.901 0)
			(layer "F.Fab")
			(effects
				(font
					(size 0.7 0.7)
					(thickness 0.15)
				)
				(justify left bottom)
			)
		)
		(fp_text user "License: Apache-2.0"
			(at -0.4 5.101 0)
			(layer "F.Fab")
			(effects
				(font
					(size 0.7 0.7)
					(thickness 0.15)
				)
				(justify left bottom)
			)
		)
		(pad "1" smd circle
			(at 0 0)
			(size 0.75 0.75)
			(layers "F.Cu" "F.Mask")
			(net 534 "Net-(U39-RATE0)")
			(pinfunction "1")
			(pintype "passive")
		)
	)
)
